(kicad_pcb
	(version 20260206)
	(generator "pcbnew")
	(generator_version "10.0")
	(general
		(thickness 1.6)
		(legacy_teardrops no)
	)
	(paper "A4")
	(title_block
		(title "03242023_DA0F0TMBIJ0_F0T_Motherboard_J_brd_V01_OCP.brd")
		(comment 1 "Grand Teton / footprints 1315-1320 of 6105")
	)
	(layers
		(0 "F.Cu" signal "TOP")
		(4 "In1.Cu" signal "GND")
		(6 "In2.Cu" signal "IN1")
		(8 "In3.Cu" signal "GND1")
		(10 "In4.Cu" signal "IN2")
		(12 "In5.Cu" signal "GND2")
		(14 "In6.Cu" signal "IN3")
		(16 "In7.Cu" signal "GND3")
		(18 "In8.Cu" signal "VCC")
		(20 "In9.Cu" signal "VCC1")
		(22 "In10.Cu" signal "GND4")
		(24 "In11.Cu" signal "IN4")
		(26 "In12.Cu" signal "GND5")
		(28 "In13.Cu" signal "IN5")
		(30 "In14.Cu" signal "GND6")
		(32 "In15.Cu" signal "IN6")
		(34 "In16.Cu" signal "GND7")
		(2 "B.Cu" signal "BOTTOM")
		(9 "F.Adhes" user "F.Adhesive")
		(11 "B.Adhes" user "B.Adhesive")
		(13 "F.Paste" user "Package Geometry/Pastemask Top")
		(15 "B.Paste" user "Package Geometry/Pastemask Bottom")
		(5 "F.SilkS" user "Ref Des/Silkscreen Top")
		(7 "B.SilkS" user "Ref Des/Silkscreen Bottom")
		(1 "F.Mask" user "Board Geometry/Soldermask Top")
		(3 "B.Mask" user "Board Geometry/Soldermask Bottom")
		(17 "Dwgs.User" user "User.Drawings")
		(19 "Cmts.User" user "User.Comments")
		(21 "Eco1.User" user "User.Eco1")
		(23 "Eco2.User" user "User.Eco2")
		(25 "Edge.Cuts" user "Board Geometry/Outline")
		(27 "Margin" user)
		(31 "F.CrtYd" user "Package Geometry/Place Bound Top")
		(29 "B.CrtYd" user "Package Geometry/Place Bound Bottom")
		(35 "F.Fab" user "Ref Des/Assembly Top")
		(33 "B.Fab" user "Ref Des/Assembly Bottom")
	)
	(footprint ""
		(layer "F.Cu")
		(at 204.99578 -112.02924 180)
		(property "Reference" "R4722"
			(at 0 0 180)
			(layer "F.SilkS")
			(hide yes)
			(effects
				(font
					(size 1.27 1.27)
				)
			)
		)
		(property "Value" ""
			(at 0 0 180)
			(layer "F.Fab")
			(effects
				(font
					(size 1.27 1.27)
				)
			)
		)
		(duplicate_pad_numbers_are_jumpers no)
		(fp_line
			(start 0.7874 0.4064)
			(end -0.7874 0.4064)
			(stroke
				(width 0.1524)
				(type default)
			)
			(layer "F.SilkS")
		)
		(fp_line
			(start 0.7874 -0.4064)
			(end 0.7874 0.4064)
			(stroke
				(width 0.1524)
				(type default)
			)
			(layer "F.SilkS")
		)
		(fp_line
			(start -0.7874 0.4064)
			(end -0.7874 -0.4064)
			(stroke
				(width 0.1524)
				(type default)
			)
			(layer "F.SilkS")
		)
		(fp_line
			(start -0.7874 -0.4064)
			(end 0.7874 -0.4064)
			(stroke
				(width 0.1524)
				(type default)
			)
			(layer "F.SilkS")
		)
		(fp_line
			(start 0.67945 0.3048)
			(end 0.120396 0.3048)
			(stroke
				(width 0.1)
				(type default)
			)
			(layer "F.Fab")
		)
		(fp_line
			(start 0.67945 -0.3048)
			(end 0.67945 0.3048)
			(stroke
				(width 0.1)
				(type default)
			)
			(layer "F.Fab")
		)
		(fp_line
			(start 0.12065 -0.2794)
			(end 0.12065 -0.3048)
			(stroke
				(width 0.1)
				(type default)
			)
			(layer "F.Fab")
		)
		(fp_line
			(start 0.12065 -0.3048)
			(end 0.67945 -0.3048)
			(stroke
				(width 0.1)
				(type default)
			)
			(layer "F.Fab")
		)
		(fp_line
			(start 0.120396 0.3048)
			(end 0.120396 0.2794)
			(stroke
				(width 0.1)
				(type default)
			)
			(layer "F.Fab")
		)
		(fp_line
			(start 0.120396 0.2794)
			(end -0.12065 0.2794)
			(stroke
				(width 0.1)
				(type default)
			)
			(layer "F.Fab")
		)
		(fp_line
			(start -0.12065 0.3048)
			(end -0.67945 0.3048)
			(stroke
				(width 0.1)
				(type default)
			)
			(layer "F.Fab")
		)
		(fp_line
			(start -0.12065 0.2794)
			(end -0.12065 0.3048)
			(stroke
				(width 0.1)
				(type default)
			)
			(layer "F.Fab")
		)
		(fp_line
			(start -0.12065 -0.2794)
			(end 0.12065 -0.2794)
			(stroke
				(width 0.1)
				(type default)
			)
			(layer "F.Fab")
		)
		(fp_line
			(start -0.12065 -0.305054)
			(end -0.12065 -0.2794)
			(stroke
				(width 0.1)
				(type default)
			)
			(layer "F.Fab")
		)
		(fp_line
			(start -0.67945 0.3048)
			(end -0.67945 -0.305054)
			(stroke
				(width 0.1)
				(type default)
			)
			(layer "F.Fab")
		)
		(fp_line
			(start -0.67945 -0.305054)
			(end -0.12065 -0.305054)
			(stroke
				(width 0.1)
				(type default)
			)
			(layer "F.Fab")
		)
		(pad "1" smd circle
			(at -0.40005 0 180)
			(size 0 0)
			(layers "F.Cu" "F.Mask" "F.Paste")
			(net "FM_PCH_BMC_RST_R_N")
		)
		(pad "2" smd circle
			(at 0.40005 0 180)
			(size 0 0)
			(layers "F.Cu" "F.Mask" "F.Paste")
			(net "P3V3_AUX")
		)
	)
	(footprint ""
		(layer "F.Cu")
		(at 428.179992 -396.448534)
		(property "Reference" "Q104"
			(at 0.079248 -1.848104 0)
			(unlocked yes)
			(layer "F.SilkS")
			(effects
				(font
					(size 0.7874 0.5842)
					(thickness 0.1524)
				)
				(justify left)
			)
		)
		(property "Value" ""
			(at 0 0 0)
			(layer "F.Fab")
			(effects
				(font
					(size 1.27 1.27)
				)
			)
		)
		(duplicate_pad_numbers_are_jumpers no)
		(fp_line
			(start -1.332738 -1.100074)
			(end -0.4826 -1.100074)
			(stroke
				(width 0.1524)
				(type default)
			)
			(layer "F.SilkS")
		)
		(fp_line
			(start -1.332738 1.100074)
			(end -1.332738 -1.100074)
			(stroke
				(width 0.1524)
				(type default)
			)
			(layer "F.SilkS")
		)
		(fp_line
			(start -0.4826 -1.100074)
			(end 0 -0.541274)
			(stroke
				(width 0.1524)
				(type default)
			)
			(layer "F.SilkS")
		)
		(fp_line
			(start 0 -0.541274)
			(end 0.4826 -1.100074)
			(stroke
				(width 0.1524)
				(type default)
			)
			(layer "F.SilkS")
		)
		(fp_line
			(start 0.4826 -1.100074)
			(end 1.332738 -1.100074)
			(stroke
				(width 0.1524)
				(type default)
			)
			(layer "F.SilkS")
		)
		(fp_line
			(start 1.332738 -1.100074)
			(end 1.332738 1.100074)
			(stroke
				(width 0.1524)
				(type default)
			)
			(layer "F.SilkS")
		)
		(fp_line
			(start 1.332738 1.100074)
			(end -1.332738 1.100074)
			(stroke
				(width 0.1524)
				(type default)
			)
			(layer "F.SilkS")
		)
		(fp_poly
			(pts
				(xy -0.647192 -2.136902) (xy -0.99822 -1.434846) (xy -1.349248 -2.136902)
			)
			(stroke
				(width 0)
				(type default)
			)
			(fill yes)
			(layer "F.SilkS")
		)
		(fp_line
			(start -0.674878 -1.100074)
			(end 0.674878 -1.100074)
			(stroke
				(width 0.1)
				(type default)
			)
			(layer "F.Fab")
		)
		(fp_line
			(start -0.674878 1.100074)
			(end -0.674878 -1.100074)
			(stroke
				(width 0.1)
				(type default)
			)
			(layer "F.Fab")
		)
		(fp_line
			(start 0.674878 -1.100074)
			(end 0.674878 1.100074)
			(stroke
				(width 0.1)
				(type default)
			)
			(layer "F.Fab")
		)
		(fp_line
			(start 0.674878 1.100074)
			(end -0.674878 1.100074)
			(stroke
				(width 0.1)
				(type default)
			)
			(layer "F.Fab")
		)
		(fp_poly
			(pts
				(xy -2.2352 -0.298958) (xy -2.2352 -1.001014) (xy -1.533144 -0.649986)
			)
			(stroke
				(width 0)
				(type default)
			)
			(fill yes)
			(layer "F.Fab")
		)
		(pad "1" smd rect
			(at -0.94996 -0.649986 90)
			(size 0.4318 0.508)
			(layers "F.Cu" "F.Mask" "F.Paste")
			(net "GND")
		)
		(pad "2" smd rect
			(at -0.94996 0 90)
			(size 0.4318 0.508)
			(layers "F.Cu" "F.Mask" "F.Paste")
			(net "GPU_FPGA_OVERT_N")
		)
		(pad "3" smd rect
			(at -0.94996 0.649986 90)
			(size 0.4318 0.508)
			(layers "F.Cu" "F.Mask" "F.Paste")
			(net "GPU_FPGA_OVERT_ISO_N")
		)
		(pad "4" smd rect
			(at 0.94996 0.649986 90)
			(size 0.4318 0.508)
			(layers "F.Cu" "F.Mask" "F.Paste")
			(net "GND")
		)
		(pad "5" smd rect
			(at 0.94996 0 90)
			(size 0.4318 0.508)
			(layers "F.Cu" "F.Mask" "F.Paste")
			(net "GPU_FPGA_OVERT")
		)
		(pad "6" smd rect
			(at 0.94996 -0.649986 90)
			(size 0.4318 0.508)
			(layers "F.Cu" "F.Mask" "F.Paste")
			(net "GPU_FPGA_OVERT")
		)
	)
	(footprint ""
		(layer "F.Cu")
		(at 128.948434 -361.313476 180)
		(property "Reference" "PR1338"
			(at 0 0 180)
			(layer "F.SilkS")
			(hide yes)
			(effects
				(font
					(size 1.27 1.27)
				)
			)
		)
		(property "Value" ""
			(at 0 0 180)
			(layer "F.Fab")
			(effects
				(font
					(size 1.27 1.27)
				)
			)
		)
		(duplicate_pad_numbers_are_jumpers no)
		(fp_line
			(start 0.7874 0.4064)
			(end -0.7874 0.4064)
			(stroke
				(width 0.1524)
				(type default)
			)
			(layer "F.SilkS")
		)
		(fp_line
			(start 0.7874 -0.4064)
			(end 0.7874 0.4064)
			(stroke
				(width 0.1524)
				(type default)
			)
			(layer "F.SilkS")
		)
		(fp_line
			(start -0.7874 0.4064)
			(end -0.7874 -0.4064)
			(stroke
				(width 0.1524)
				(type default)
			)
			(layer "F.SilkS")
		)
		(fp_line
			(start -0.7874 -0.4064)
			(end 0.7874 -0.4064)
			(stroke
				(width 0.1524)
				(type default)
			)
			(layer "F.SilkS")
		)
		(fp_line
			(start 0.67945 0.3048)
			(end 0.120396 0.3048)
			(stroke
				(width 0.1)
				(type default)
			)
			(layer "F.Fab")
		)
		(fp_line
			(start 0.67945 -0.3048)
			(end 0.67945 0.3048)
			(stroke
				(width 0.1)
				(type default)
			)
			(layer "F.Fab")
		)
		(fp_line
			(start 0.12065 -0.2794)
			(end 0.12065 -0.3048)
			(stroke
				(width 0.1)
				(type default)
			)
			(layer "F.Fab")
		)
		(fp_line
			(start 0.12065 -0.3048)
			(end 0.67945 -0.3048)
			(stroke
				(width 0.1)
				(type default)
			)
			(layer "F.Fab")
		)
		(fp_line
			(start 0.120396 0.3048)
			(end 0.120396 0.2794)
			(stroke
				(width 0.1)
				(type default)
			)
			(layer "F.Fab")
		)
		(fp_line
			(start 0.120396 0.2794)
			(end -0.12065 0.2794)
			(stroke
				(width 0.1)
				(type default)
			)
			(layer "F.Fab")
		)
		(fp_line
			(start -0.12065 0.3048)
			(end -0.67945 0.3048)
			(stroke
				(width 0.1)
				(type default)
			)
			(layer "F.Fab")
		)
		(fp_line
			(start -0.12065 0.2794)
			(end -0.12065 0.3048)
			(stroke
				(width 0.1)
				(type default)
			)
			(layer "F.Fab")
		)
		(fp_line
			(start -0.12065 -0.2794)
			(end 0.12065 -0.2794)
			(stroke
				(width 0.1)
				(type default)
			)
			(layer "F.Fab")
		)
		(fp_line
			(start -0.12065 -0.305054)
			(end -0.12065 -0.2794)
			(stroke
				(width 0.1)
				(type default)
			)
			(layer "F.Fab")
		)
		(fp_line
			(start -0.67945 0.3048)
			(end -0.67945 -0.305054)
			(stroke
				(width 0.1)
				(type default)
			)
			(layer "F.Fab")
		)
		(fp_line
			(start -0.67945 -0.305054)
			(end -0.12065 -0.305054)
			(stroke
				(width 0.1)
				(type default)
			)
			(layer "F.Fab")
		)
		(pad "1" smd circle
			(at -0.40005 0 180)
			(size 0 0)
			(layers "F.Cu" "F.Mask" "F.Paste")
			(net "P3V3_AUX")
		)
		(pad "2" smd circle
			(at 0.40005 0 180)
			(size 0 0)
			(layers "F.Cu" "F.Mask" "F.Paste")
			(net "PVPP_HBM_CPU1_VCC")
		)
	)
	(footprint ""
		(layer "F.Cu")
		(at 465.823554 -115.295934 180)
		(property "Reference" "R1127"
			(at 0 0 180)
			(layer "F.SilkS")
			(hide yes)
			(effects
				(font
					(size 1.27 1.27)
				)
			)
		)
		(property "Value" ""
			(at 0 0 180)
			(layer "F.Fab")
			(effects
				(font
					(size 1.27 1.27)
				)
			)
		)
		(duplicate_pad_numbers_are_jumpers no)
		(fp_line
			(start 0.7874 0.4064)
			(end -0.7874 0.4064)
			(stroke
				(width 0.1524)
				(type default)
			)
			(layer "F.SilkS")
		)
		(fp_line
			(start 0.7874 -0.4064)
			(end 0.7874 0.4064)
			(stroke
				(width 0.1524)
				(type default)
			)
			(layer "F.SilkS")
		)
		(fp_line
			(start -0.7874 0.4064)
			(end -0.7874 -0.4064)
			(stroke
				(width 0.1524)
				(type default)
			)
			(layer "F.SilkS")
		)
		(fp_line
			(start -0.7874 -0.4064)
			(end 0.7874 -0.4064)
			(stroke
				(width 0.1524)
				(type default)
			)
			(layer "F.SilkS")
		)
		(fp_line
			(start 0.67945 0.3048)
			(end 0.120396 0.3048)
			(stroke
				(width 0.1)
				(type default)
			)
			(layer "F.Fab")
		)
		(fp_line
			(start 0.67945 -0.3048)
			(end 0.67945 0.3048)
			(stroke
				(width 0.1)
				(type default)
			)
			(layer "F.Fab")
		)
		(fp_line
			(start 0.12065 -0.2794)
			(end 0.12065 -0.3048)
			(stroke
				(width 0.1)
				(type default)
			)
			(layer "F.Fab")
		)
		(fp_line
			(start 0.12065 -0.3048)
			(end 0.67945 -0.3048)
			(stroke
				(width 0.1)
				(type default)
			)
			(layer "F.Fab")
		)
		(fp_line
			(start 0.120396 0.3048)
			(end 0.120396 0.2794)
			(stroke
				(width 0.1)
				(type default)
			)
			(layer "F.Fab")
		)
		(fp_line
			(start 0.120396 0.2794)
			(end -0.12065 0.2794)
			(stroke
				(width 0.1)
				(type default)
			)
			(layer "F.Fab")
		)
		(fp_line
			(start -0.12065 0.3048)
			(end -0.67945 0.3048)
			(stroke
				(width 0.1)
				(type default)
			)
			(layer "F.Fab")
		)
		(fp_line
			(start -0.12065 0.2794)
			(end -0.12065 0.3048)
			(stroke
				(width 0.1)
				(type default)
			)
			(layer "F.Fab")
		)
		(fp_line
			(start -0.12065 -0.2794)
			(end 0.12065 -0.2794)
			(stroke
				(width 0.1)
				(type default)
			)
			(layer "F.Fab")
		)
		(fp_line
			(start -0.12065 -0.305054)
			(end -0.12065 -0.2794)
			(stroke
				(width 0.1)
				(type default)
			)
			(layer "F.Fab")
		)
		(fp_line
			(start -0.67945 0.3048)
			(end -0.67945 -0.305054)
			(stroke
				(width 0.1)
				(type default)
			)
			(layer "F.Fab")
		)
		(fp_line
			(start -0.67945 -0.305054)
			(end -0.12065 -0.305054)
			(stroke
				(width 0.1)
				(type default)
			)
			(layer "F.Fab")
		)
		(pad "1" smd circle
			(at -0.40005 0 180)
			(size 0 0)
			(layers "F.Cu" "F.Mask" "F.Paste")
			(net "P3V3_AUX")
		)
		(pad "2" smd circle
			(at 0.40005 0 180)
			(size 0 0)
			(layers "F.Cu" "F.Mask" "F.Paste")
			(net "PD_SMB_OCP1_HP_ADD0")
		)
	)
	(footprint ""
		(layer "F.Cu")
		(at 303.9872 -25.8064 180)
		(property "Reference" "R4787"
			(at 0 0 180)
			(layer "F.SilkS")
			(hide yes)
			(effects
				(font
					(size 1.27 1.27)
				)
			)
		)
		(property "Value" ""
			(at 0 0 180)
			(layer "F.Fab")
			(effects
				(font
					(size 1.27 1.27)
				)
			)
		)
		(duplicate_pad_numbers_are_jumpers no)
		(fp_line
			(start 0.7874 0.4064)
			(end -0.7874 0.4064)
			(stroke
				(width 0.1524)
				(type default)
			)
			(layer "F.SilkS")
		)
		(fp_line
			(start 0.7874 -0.4064)
			(end 0.7874 0.4064)
			(stroke
				(width 0.1524)
				(type default)
			)
			(layer "F.SilkS")
		)
		(fp_line
			(start -0.7874 0.4064)
			(end -0.7874 -0.4064)
			(stroke
				(width 0.1524)
				(type default)
			)
			(layer "F.SilkS")
		)
		(fp_line
			(start -0.7874 -0.4064)
			(end 0.7874 -0.4064)
			(stroke
				(width 0.1524)
				(type default)
			)
			(layer "F.SilkS")
		)
		(fp_line
			(start 0.67945 0.3048)
			(end 0.120396 0.3048)
			(stroke
				(width 0.1)
				(type default)
			)
			(layer "F.Fab")
		)
		(fp_line
			(start 0.67945 -0.3048)
			(end 0.67945 0.3048)
			(stroke
				(width 0.1)
				(type default)
			)
			(layer "F.Fab")
		)
		(fp_line
			(start 0.12065 -0.2794)
			(end 0.12065 -0.3048)
			(stroke
				(width 0.1)
				(type default)
			)
			(layer "F.Fab")
		)
		(fp_line
			(start 0.12065 -0.3048)
			(end 0.67945 -0.3048)
			(stroke
				(width 0.1)
				(type default)
			)
			(layer "F.Fab")
		)
		(fp_line
			(start 0.120396 0.3048)
			(end 0.120396 0.2794)
			(stroke
				(width 0.1)
				(type default)
			)
			(layer "F.Fab")
		)
		(fp_line
			(start 0.120396 0.2794)
			(end -0.12065 0.2794)
			(stroke
				(width 0.1)
				(type default)
			)
			(layer "F.Fab")
		)
		(fp_line
			(start -0.12065 0.3048)
			(end -0.67945 0.3048)
			(stroke
				(width 0.1)
				(type default)
			)
			(layer "F.Fab")
		)
		(fp_line
			(start -0.12065 0.2794)
			(end -0.12065 0.3048)
			(stroke
				(width 0.1)
				(type default)
			)
			(layer "F.Fab")
		)
		(fp_line
			(start -0.12065 -0.2794)
			(end 0.12065 -0.2794)
			(stroke
				(width 0.1)
				(type default)
			)
			(layer "F.Fab")
		)
		(fp_line
			(start -0.12065 -0.305054)
			(end -0.12065 -0.2794)
			(stroke
				(width 0.1)
				(type default)
			)
			(layer "F.Fab")
		)
		(fp_line
			(start -0.67945 0.3048)
			(end -0.67945 -0.305054)
			(stroke
				(width 0.1)
				(type default)
			)
			(layer "F.Fab")
		)
		(fp_line
			(start -0.67945 -0.305054)
			(end -0.12065 -0.305054)
			(stroke
				(width 0.1)
				(type default)
			)
			(layer "F.Fab")
		)
		(pad "1" smd circle
			(at -0.40005 0 180)
			(size 0 0)
			(layers "F.Cu" "F.Mask" "F.Paste")
			(net "PWRGD_DSW_PWROK_TRIGGER")
		)
		(pad "2" smd circle
			(at 0.40005 0 180)
			(size 0 0)
			(layers "F.Cu" "F.Mask" "F.Paste")
			(net "PWRGD_DSW_PWROK_R5")
		)
	)
	(footprint ""
		(layer "F.Cu")
		(at 150.67788 -47.970948 90)
		(property "Reference" "R3573"
			(at 0 0 90)
			(layer "F.SilkS")
			(hide yes)
			(effects
				(font
					(size 1.27 1.27)
				)
			)
		)
		(property "Value" ""
			(at 0 0 90)
			(layer "F.Fab")
			(effects
				(font
					(size 1.27 1.27)
				)
			)
		)
		(duplicate_pad_numbers_are_jumpers no)
		(fp_line
			(start 0.7874 -0.4064)
			(end 0.7874 0.4064)
			(stroke
				(width 0.1524)
				(type default)
			)
			(layer "F.SilkS")
		)
		(fp_line
			(start -0.7874 -0.4064)
			(end 0.7874 -0.4064)
			(stroke
				(width 0.1524)
				(type default)
			)
			(layer "F.SilkS")
		)
		(fp_line
			(start 0.7874 0.4064)
			(end -0.7874 0.4064)
			(stroke
				(width 0.1524)
				(type default)
			)
			(layer "F.SilkS")
		)
		(fp_line
			(start -0.7874 0.4064)
			(end -0.7874 -0.4064)
			(stroke
				(width 0.1524)
				(type default)
			)
			(layer "F.SilkS")
		)
		(fp_line
			(start -0.12065 -0.305054)
			(end -0.12065 -0.2794)
			(stroke
				(width 0.1)
				(type default)
			)
			(layer "F.Fab")
		)
		(fp_line
			(start -0.67945 -0.305054)
			(end -0.12065 -0.305054)
			(stroke
				(width 0.1)
				(type default)
			)
			(layer "F.Fab")
		)
		(fp_line
			(start 0.67945 -0.3048)
			(end 0.67945 0.3048)
			(stroke
				(width 0.1)
				(type default)
			)
			(layer "F.Fab")
		)
		(fp_line
			(start 0.12065 -0.3048)
			(end 0.67945 -0.3048)
			(stroke
				(width 0.1)
				(type default)
			)
			(layer "F.Fab")
		)
		(fp_line
			(start 0.12065 -0.2794)
			(end 0.12065 -0.3048)
			(stroke
				(width 0.1)
				(type default)
			)
			(layer "F.Fab")
		)
		(fp_line
			(start -0.12065 -0.2794)
			(end 0.12065 -0.2794)
			(stroke
				(width 0.1)
				(type default)
			)
			(layer "F.Fab")
		)
		(fp_line
			(start 0.120396 0.2794)
			(end -0.12065 0.2794)
			(stroke
				(width 0.1)
				(type default)
			)
			(layer "F.Fab")
		)
		(fp_line
			(start -0.12065 0.2794)
			(end -0.12065 0.3048)
			(stroke
				(width 0.1)
				(type default)
			)
			(layer "F.Fab")
		)
		(fp_line
			(start 0.67945 0.3048)
			(end 0.120396 0.3048)
			(stroke
				(width 0.1)
				(type default)
			)
			(layer "F.Fab")
		)
		(fp_line
			(start 0.120396 0.3048)
			(end 0.120396 0.2794)
			(stroke
				(width 0.1)
				(type default)
			)
			(layer "F.Fab")
		)
		(fp_line
			(start -0.12065 0.3048)
			(end -0.67945 0.3048)
			(stroke
				(width 0.1)
				(type default)
			)
			(layer "F.Fab")
		)
		(fp_line
			(start -0.67945 0.3048)
			(end -0.67945 -0.305054)
			(stroke
				(width 0.1)
				(type default)
			)
			(layer "F.Fab")
		)
		(pad "1" smd circle
			(at -0.40005 0 90)
			(size 0 0)
			(layers "F.Cu" "F.Mask" "F.Paste")
			(net "SMB_INA230_4_3V3AUX_SDA_R")
		)
		(pad "2" smd circle
			(at 0.40005 0 90)
			(size 0 0)
			(layers "F.Cu" "F.Mask" "F.Paste")
			(net "SMB_INA230_4_3V3AUX_SDA_R1")
		)
	)
)
